(kicad_pcb
	(version 20260206)
	(generator "pcbnew")
	(generator_version "10.0")
	(general
		(thickness 1.6)
		(legacy_teardrops no)
	)
	(paper "A4")
	(title_block
		(title "peb — Lightning_PEB_BRD.brd")
		(comment 1 "Lightning (Wiwynn / Facebook NVMe JBOF) / footprints 1935-1942 of 2563")
	)
	(layers
		(0 "F.Cu" signal "TOP")
		(4 "In1.Cu" signal "L2GND")
		(6 "In2.Cu" signal "L3")
		(8 "In3.Cu" signal "L4VCC")
		(10 "In4.Cu" signal "L5VCC")
		(12 "In5.Cu" signal "L6")
		(14 "In6.Cu" signal "L7GND")
		(2 "B.Cu" signal "BOTTOM")
		(9 "F.Adhes" user "F.Adhesive")
		(11 "B.Adhes" user "B.Adhesive")
		(13 "F.Paste" user "Package Geometry/Pastemask Top")
		(15 "B.Paste" user "Package Geometry/Pastemask Bottom")
		(5 "F.SilkS" user "Ref Des/Silkscreen Top")
		(7 "B.SilkS" user "Ref Des/Silkscreen Bottom")
		(1 "F.Mask" user "Board Geometry/Soldermask Top")
		(3 "B.Mask" user "Board Geometry/Soldermask Bottom")
		(17 "Dwgs.User" user "User.Drawings")
		(19 "Cmts.User" user "User.Comments")
		(21 "Eco1.User" user "User.Eco1")
		(23 "Eco2.User" user "User.Eco2")
		(25 "Edge.Cuts" user "Board Geometry/Outline")
		(27 "Margin" user)
		(31 "F.CrtYd" user "Package Geometry/Place Bound Top")
		(29 "B.CrtYd" user "Package Geometry/Place Bound Bottom")
		(35 "F.Fab" user "Ref Des/Assembly Top")
		(33 "B.Fab" user "Ref Des/Assembly Bottom")
	)
	(footprint ""
		(layer "B.Cu")
		(at 226.568 -59.9948 -90)
		(property "Reference" "C544"
			(at 0 0 90)
			(layer "B.SilkS")
			(hide yes)
			(effects
				(font
					(size 1.27 1.27)
				)
				(justify mirror)
			)
		)
		(property "Value" "SCD1U16V1KX-1-GP"
			(at 2.8321 -1.7399 270)
			(unlocked yes)
			(layer "B.Fab")
			(hide yes)
			(effects
				(font
					(size 1.016 1.016)
					(thickness 0.1524)
				)
				(justify mirror)
			)
		)
		(property "Device Type" "C0201H13"
			(at 2.8321 -3.2639 270)
			(unlocked yes)
			(layer "B.Fab")
			(hide yes)
			(effects
				(font
					(size 1.016 1.016)
					(thickness 0.1524)
				)
				(justify mirror)
			)
		)
		(duplicate_pad_numbers_are_jumpers no)
		(fp_rect
			(start 0.2794 0.6477)
			(end -0.2794 -0.6477)
			(stroke
				(width 0)
				(type default)
			)
			(fill no)
			(layer "B.CrtYd")
		)
		(fp_rect
			(start 0.2794 0.6477)
			(end -0.2794 -0.6477)
			(stroke
				(width 0)
				(type default)
			)
			(fill no)
			(layer "B.Fab")
		)
		(pad "1" smd custom
			(at 0 -0.2794 90)
			(size 0.0762 0.0762)
			(layers "B.Cu" "B.Mask" "B.Paste")
			(net "DUT_AVD_PCIE")
			(options
				(clearance outline)
				(anchor circle)
			)
			(primitives
				(gr_poly
					(pts
						(arc
							(start 0.1524 0.127)
							(mid 0.137521 0.162921)
							(end 0.1016 0.1778)
						)
						(arc
							(start -0.1016 0.1778)
							(mid -0.137521 0.162921)
							(end -0.1524 0.127)
						)
						(arc
							(start -0.1524 -0.127)
							(mid -0.137521 -0.162921)
							(end -0.1016 -0.1778)
						)
						(arc
							(start 0.1016 -0.1778)
							(mid 0.137521 -0.162921)
							(end 0.1524 -0.127)
						)
					)
					(width 0)
					(fill yes)
				)
			)
		)
		(pad "2" smd custom
			(at 0 0.2794 90)
			(size 0.0762 0.0762)
			(layers "B.Cu" "B.Mask" "B.Paste")
			(net "GND")
			(options
				(clearance outline)
				(anchor circle)
			)
			(primitives
				(gr_poly
					(pts
						(arc
							(start 0.1524 0.127)
							(mid 0.137521 0.162921)
							(end 0.1016 0.1778)
						)
						(arc
							(start -0.1016 0.1778)
							(mid -0.137521 0.162921)
							(end -0.1524 0.127)
						)
						(arc
							(start -0.1524 -0.127)
							(mid -0.137521 -0.162921)
							(end -0.1016 -0.1778)
						)
						(arc
							(start 0.1016 -0.1778)
							(mid 0.137521 -0.162921)
							(end 0.1524 -0.127)
						)
					)
					(width 0)
					(fill yes)
				)
			)
		)
	)
	(footprint ""
		(layer "B.Cu")
		(at 82.145124 -195.427092 180)
		(property "Reference" "R4111"
			(at 0 0 0)
			(layer "B.SilkS")
			(hide yes)
			(effects
				(font
					(size 1.27 1.27)
				)
				(justify mirror)
			)
		)
		(property "Value" "4K7R2F-GP"
			(at -0.064008 -3.993896 180)
			(unlocked yes)
			(layer "B.Fab")
			(hide yes)
			(effects
				(font
					(size 1.016 1.016)
					(thickness 0.1524)
				)
				(justify mirror)
			)
		)
		(property "Device Type" "R402H16"
			(at -0.064008 -5.517896 180)
			(unlocked yes)
			(layer "B.Fab")
			(hide yes)
			(effects
				(font
					(size 1.016 1.016)
					(thickness 0.1524)
				)
				(justify mirror)
			)
		)
		(duplicate_pad_numbers_are_jumpers no)
		(fp_line
			(start 0.508 -0.9398)
			(end 0.508 0.9398)
			(stroke
				(width 0.1524)
				(type default)
			)
			(layer "B.SilkS")
		)
		(fp_line
			(start -0.508 -0.9398)
			(end 0.508 -0.9398)
			(stroke
				(width 0.1524)
				(type default)
			)
			(layer "B.SilkS")
		)
		(fp_rect
			(start 0.508 0.9398)
			(end -0.508 -0.9398)
			(stroke
				(width 0)
				(type default)
			)
			(fill no)
			(layer "B.CrtYd")
		)
		(fp_rect
			(start 0.508 0.9398)
			(end -0.508 -0.9398)
			(stroke
				(width 0)
				(type default)
			)
			(fill no)
			(layer "B.Fab")
		)
		(pad "1" smd custom
			(at 0 -0.4445)
			(size 0.1397 0.1397)
			(layers "B.Cu" "B.Mask" "B.Paste")
			(net "SSD_PRSNT#10")
			(options
				(clearance outline)
				(anchor circle)
			)
			(primitives
				(gr_poly
					(pts
						(arc
							(start -0.1778 0.2794)
							(mid -0.249642 0.249642)
							(end -0.2794 0.1778)
						)
						(arc
							(start -0.2794 -0.1778)
							(mid -0.249642 -0.249642)
							(end -0.1778 -0.2794)
						)
						(arc
							(start 0.1778 -0.2794)
							(mid 0.249642 -0.249642)
							(end 0.2794 -0.1778)
						)
						(arc
							(start 0.2794 0.1778)
							(mid 0.249642 0.249642)
							(end 0.1778 0.2794)
						)
					)
					(width 0)
					(fill yes)
				)
			)
		)
		(pad "2" smd custom
			(at 0 0.4445)
			(size 0.1397 0.1397)
			(layers "B.Cu" "B.Mask" "B.Paste")
			(net "P3V3_STBY")
			(options
				(clearance outline)
				(anchor circle)
			)
			(primitives
				(gr_poly
					(pts
						(arc
							(start -0.1778 0.2794)
							(mid -0.249642 0.249642)
							(end -0.2794 0.1778)
						)
						(arc
							(start -0.2794 -0.1778)
							(mid -0.249642 -0.249642)
							(end -0.1778 -0.2794)
						)
						(arc
							(start 0.1778 -0.2794)
							(mid 0.249642 -0.249642)
							(end 0.2794 -0.1778)
						)
						(arc
							(start 0.2794 0.1778)
							(mid 0.249642 0.249642)
							(end 0.1778 0.2794)
						)
					)
					(width 0)
					(fill yes)
				)
			)
		)
	)
	(footprint ""
		(layer "B.Cu")
		(at 75.184 -146.939 -90)
		(property "Reference" "R192"
			(at 0 0 90)
			(layer "B.SilkS")
			(hide yes)
			(effects
				(font
					(size 1.27 1.27)
				)
				(justify mirror)
			)
		)
		(property "Value" "8K2R2J-3-GP"
			(at -0.064008 -3.993896 270)
			(unlocked yes)
			(layer "B.Fab")
			(hide yes)
			(effects
				(font
					(size 1.016 1.016)
					(thickness 0.1524)
				)
				(justify mirror)
			)
		)
		(property "Device Type" "R402H16"
			(at -0.064008 -5.517896 270)
			(unlocked yes)
			(layer "B.Fab")
			(hide yes)
			(effects
				(font
					(size 1.016 1.016)
					(thickness 0.1524)
				)
				(justify mirror)
			)
		)
		(duplicate_pad_numbers_are_jumpers no)
		(fp_line
			(start -0.508 -0.9398)
			(end 0.508 -0.9398)
			(stroke
				(width 0.1524)
				(type default)
			)
			(layer "B.SilkS")
		)
		(fp_line
			(start 0.508 -0.9398)
			(end 0.508 0.9398)
			(stroke
				(width 0.1524)
				(type default)
			)
			(layer "B.SilkS")
		)
		(fp_rect
			(start 0.508 0.9398)
			(end -0.508 -0.9398)
			(stroke
				(width 0)
				(type default)
			)
			(fill no)
			(layer "B.CrtYd")
		)
		(fp_rect
			(start 0.508 0.9398)
			(end -0.508 -0.9398)
			(stroke
				(width 0)
				(type default)
			)
			(fill no)
			(layer "B.Fab")
		)
		(pad "1" smd custom
			(at 0 -0.4445 90)
			(size 0.1397 0.1397)
			(layers "B.Cu" "B.Mask" "B.Paste")
			(net "P3V3_STBY")
			(options
				(clearance outline)
				(anchor circle)
			)
			(primitives
				(gr_poly
					(pts
						(arc
							(start -0.1778 0.2794)
							(mid -0.249642 0.249642)
							(end -0.2794 0.1778)
						)
						(arc
							(start -0.2794 -0.1778)
							(mid -0.249642 -0.249642)
							(end -0.1778 -0.2794)
						)
						(arc
							(start 0.1778 -0.2794)
							(mid 0.249642 -0.249642)
							(end 0.2794 -0.1778)
						)
						(arc
							(start 0.2794 0.1778)
							(mid 0.249642 0.249642)
							(end 0.1778 0.2794)
						)
					)
					(width 0)
					(fill yes)
				)
			)
		)
		(pad "2" smd custom
			(at 0 0.4445 90)
			(size 0.1397 0.1397)
			(layers "B.Cu" "B.Mask" "B.Paste")
			(net "EEPROM_A0_R")
			(options
				(clearance outline)
				(anchor circle)
			)
			(primitives
				(gr_poly
					(pts
						(arc
							(start -0.1778 0.2794)
							(mid -0.249642 0.249642)
							(end -0.2794 0.1778)
						)
						(arc
							(start -0.2794 -0.1778)
							(mid -0.249642 -0.249642)
							(end -0.1778 -0.2794)
						)
						(arc
							(start 0.1778 -0.2794)
							(mid 0.249642 -0.249642)
							(end 0.2794 -0.1778)
						)
						(arc
							(start 0.2794 0.1778)
							(mid 0.249642 0.249642)
							(end 0.1778 0.2794)
						)
					)
					(width 0)
					(fill yes)
				)
			)
		)
	)
	(footprint ""
		(layer "B.Cu")
		(at 54.031642 -122.860816 -90)
		(property "Reference" "R467"
			(at 0 0 90)
			(layer "B.SilkS")
			(hide yes)
			(effects
				(font
					(size 1.27 1.27)
				)
				(justify mirror)
			)
		)
		(property "Value" "0R2J-2-GP"
			(at -0.064008 -3.993896 270)
			(unlocked yes)
			(layer "B.Fab")
			(hide yes)
			(effects
				(font
					(size 1.016 1.016)
					(thickness 0.1524)
				)
				(justify mirror)
			)
		)
		(property "Device Type" "R402H16"
			(at -0.064008 -5.517896 270)
			(unlocked yes)
			(layer "B.Fab")
			(hide yes)
			(effects
				(font
					(size 1.016 1.016)
					(thickness 0.1524)
				)
				(justify mirror)
			)
		)
		(duplicate_pad_numbers_are_jumpers no)
		(fp_line
			(start -0.508 -0.9398)
			(end 0.508 -0.9398)
			(stroke
				(width 0.1524)
				(type default)
			)
			(layer "B.SilkS")
		)
		(fp_line
			(start 0.508 -0.9398)
			(end 0.508 0.9398)
			(stroke
				(width 0.1524)
				(type default)
			)
			(layer "B.SilkS")
		)
		(fp_rect
			(start 0.508 0.9398)
			(end -0.508 -0.9398)
			(stroke
				(width 0)
				(type default)
			)
			(fill no)
			(layer "B.CrtYd")
		)
		(fp_rect
			(start 0.508 0.9398)
			(end -0.508 -0.9398)
			(stroke
				(width 0)
				(type default)
			)
			(fill no)
			(layer "B.Fab")
		)
		(pad "1" smd custom
			(at 0 -0.4445 90)
			(size 0.1397 0.1397)
			(layers "B.Cu" "B.Mask" "B.Paste")
			(net "BMC_I2C8_CLKBUF1_SDA")
			(options
				(clearance outline)
				(anchor circle)
			)
			(primitives
				(gr_poly
					(pts
						(arc
							(start -0.1778 0.2794)
							(mid -0.249642 0.249642)
							(end -0.2794 0.1778)
						)
						(arc
							(start -0.2794 -0.1778)
							(mid -0.249642 -0.249642)
							(end -0.1778 -0.2794)
						)
						(arc
							(start 0.1778 -0.2794)
							(mid 0.249642 -0.249642)
							(end 0.2794 -0.1778)
						)
						(arc
							(start 0.2794 0.1778)
							(mid 0.249642 0.249642)
							(end 0.1778 0.2794)
						)
					)
					(width 0)
					(fill yes)
				)
			)
		)
		(pad "2" smd custom
			(at 0 0.4445 90)
			(size 0.1397 0.1397)
			(layers "B.Cu" "B.Mask" "B.Paste")
			(net "BMC0_SMB8_DAT")
			(options
				(clearance outline)
				(anchor circle)
			)
			(primitives
				(gr_poly
					(pts
						(arc
							(start -0.1778 0.2794)
							(mid -0.249642 0.249642)
							(end -0.2794 0.1778)
						)
						(arc
							(start -0.2794 -0.1778)
							(mid -0.249642 -0.249642)
							(end -0.1778 -0.2794)
						)
						(arc
							(start 0.1778 -0.2794)
							(mid 0.249642 -0.249642)
							(end 0.2794 -0.1778)
						)
						(arc
							(start 0.2794 0.1778)
							(mid 0.249642 0.249642)
							(end 0.1778 0.2794)
						)
					)
					(width 0)
					(fill yes)
				)
			)
		)
	)
	(footprint ""
		(layer "B.Cu")
		(at 181.64302 -12.0396 180)
		(property "Reference" "R303"
			(at 0 0 0)
			(layer "B.SilkS")
			(hide yes)
			(effects
				(font
					(size 1.27 1.27)
				)
				(justify mirror)
			)
		)
		(property "Value" "0R2J-2-GP"
			(at -0.064008 -3.993896 180)
			(unlocked yes)
			(layer "B.Fab")
			(hide yes)
			(effects
				(font
					(size 1.016 1.016)
					(thickness 0.1524)
				)
				(justify mirror)
			)
		)
		(property "Device Type" "R402H16"
			(at -0.064008 -5.517896 180)
			(unlocked yes)
			(layer "B.Fab")
			(hide yes)
			(effects
				(font
					(size 1.016 1.016)
					(thickness 0.1524)
				)
				(justify mirror)
			)
		)
		(duplicate_pad_numbers_are_jumpers no)
		(fp_line
			(start 0.508 -0.9398)
			(end 0.508 0.9398)
			(stroke
				(width 0.1524)
				(type default)
			)
			(layer "B.SilkS")
		)
		(fp_line
			(start -0.508 -0.9398)
			(end 0.508 -0.9398)
			(stroke
				(width 0.1524)
				(type default)
			)
			(layer "B.SilkS")
		)
		(fp_rect
			(start 0.508 0.9398)
			(end -0.508 -0.9398)
			(stroke
				(width 0)
				(type default)
			)
			(fill no)
			(layer "B.CrtYd")
		)
		(fp_rect
			(start 0.508 0.9398)
			(end -0.508 -0.9398)
			(stroke
				(width 0)
				(type default)
			)
			(fill no)
			(layer "B.Fab")
		)
		(pad "1" smd custom
			(at 0 -0.4445)
			(size 0.1397 0.1397)
			(layers "B.Cu" "B.Mask" "B.Paste")
			(net "CLK_P_3_R")
			(options
				(clearance outline)
				(anchor circle)
			)
			(primitives
				(gr_poly
					(pts
						(arc
							(start -0.1778 0.2794)
							(mid -0.249642 0.249642)
							(end -0.2794 0.1778)
						)
						(arc
							(start -0.2794 -0.1778)
							(mid -0.249642 -0.249642)
							(end -0.1778 -0.2794)
						)
						(arc
							(start 0.1778 -0.2794)
							(mid 0.249642 -0.249642)
							(end 0.2794 -0.1778)
						)
						(arc
							(start 0.2794 0.1778)
							(mid 0.249642 0.249642)
							(end 0.1778 0.2794)
						)
					)
					(width 0)
					(fill yes)
				)
			)
		)
		(pad "2" smd custom
			(at 0 0.4445)
			(size 0.1397 0.1397)
			(layers "B.Cu" "B.Mask" "B.Paste")
			(net "PCIE_REFCLK_H3_P_R")
			(options
				(clearance outline)
				(anchor circle)
			)
			(primitives
				(gr_poly
					(pts
						(arc
							(start -0.1778 0.2794)
							(mid -0.249642 0.249642)
							(end -0.2794 0.1778)
						)
						(arc
							(start -0.2794 -0.1778)
							(mid -0.249642 -0.249642)
							(end -0.1778 -0.2794)
						)
						(arc
							(start 0.1778 -0.2794)
							(mid 0.249642 -0.249642)
							(end 0.2794 -0.1778)
						)
						(arc
							(start 0.2794 0.1778)
							(mid 0.249642 0.249642)
							(end 0.1778 0.2794)
						)
					)
					(width 0)
					(fill yes)
				)
			)
		)
	)
	(footprint ""
		(layer "B.Cu")
		(at 240.538 -23.241)
		(property "Reference" "R798"
			(at 0 0 0)
			(layer "B.SilkS")
			(hide yes)
			(effects
				(font
					(size 1.27 1.27)
				)
				(justify mirror)
			)
		)
		(property "Value" "4K7R2F-GP"
			(at -0.064008 -3.993896 0)
			(unlocked yes)
			(layer "B.Fab")
			(hide yes)
			(effects
				(font
					(size 1.016 1.016)
					(thickness 0.1524)
				)
				(justify mirror)
			)
		)
		(property "Device Type" "R402H16"
			(at -0.064008 -5.517896 0)
			(unlocked yes)
			(layer "B.Fab")
			(hide yes)
			(effects
				(font
					(size 1.016 1.016)
					(thickness 0.1524)
				)
				(justify mirror)
			)
		)
		(duplicate_pad_numbers_are_jumpers no)
		(fp_line
			(start -0.508 -0.9398)
			(end 0.508 -0.9398)
			(stroke
				(width 0.1524)
				(type default)
			)
			(layer "B.SilkS")
		)
		(fp_line
			(start 0.508 -0.9398)
			(end 0.508 0.9398)
			(stroke
				(width 0.1524)
				(type default)
			)
			(layer "B.SilkS")
		)
		(fp_rect
			(start 0.508 0.9398)
			(end -0.508 -0.9398)
			(stroke
				(width 0)
				(type default)
			)
			(fill no)
			(layer "B.CrtYd")
		)
		(fp_rect
			(start 0.508 0.9398)
			(end -0.508 -0.9398)
			(stroke
				(width 0)
				(type default)
			)
			(fill no)
			(layer "B.Fab")
		)
		(pad "1" smd custom
			(at 0 -0.4445 180)
			(size 0.1397 0.1397)
			(layers "B.Cu" "B.Mask" "B.Paste")
			(net "GND")
			(options
				(clearance outline)
				(anchor circle)
			)
			(primitives
				(gr_poly
					(pts
						(arc
							(start -0.1778 0.2794)
							(mid -0.249642 0.249642)
							(end -0.2794 0.1778)
						)
						(arc
							(start -0.2794 -0.1778)
							(mid -0.249642 -0.249642)
							(end -0.1778 -0.2794)
						)
						(arc
							(start 0.1778 -0.2794)
							(mid 0.249642 -0.249642)
							(end 0.2794 -0.1778)
						)
						(arc
							(start 0.2794 0.1778)
							(mid 0.249642 0.249642)
							(end 0.1778 0.2794)
						)
					)
					(width 0)
					(fill yes)
				)
			)
		)
		(pad "2" smd custom
			(at 0 0.4445 180)
			(size 0.1397 0.1397)
			(layers "B.Cu" "B.Mask" "B.Paste")
			(net "BOOTSTRAP3")
			(options
				(clearance outline)
				(anchor circle)
			)
			(primitives
				(gr_poly
					(pts
						(arc
							(start -0.1778 0.2794)
							(mid -0.249642 0.249642)
							(end -0.2794 0.1778)
						)
						(arc
							(start -0.2794 -0.1778)
							(mid -0.249642 -0.249642)
							(end -0.1778 -0.2794)
						)
						(arc
							(start 0.1778 -0.2794)
							(mid 0.249642 -0.249642)
							(end 0.2794 -0.1778)
						)
						(arc
							(start 0.2794 0.1778)
							(mid 0.249642 0.249642)
							(end 0.1778 0.2794)
						)
					)
					(width 0)
					(fill yes)
				)
			)
		)
	)
	(footprint ""
		(layer "B.Cu")
		(at 340.995 -60.96 -90)
		(property "Reference" "PC170"
			(at 0 0 90)
			(layer "B.SilkS")
			(hide yes)
			(effects
				(font
					(size 1.27 1.27)
				)
				(justify mirror)
			)
		)
		(property "Value" "SC10U25V5KX-GP"
			(at 0.0762 -6.1214 270)
			(unlocked yes)
			(layer "B.Fab")
			(hide yes)
			(effects
				(font
					(size 1.016 1.016)
					(thickness 0.1524)
				)
				(justify mirror)
			)
		)
		(property "Device Type" "C805H56"
			(at 0.0762 -8.1534 270)
			(unlocked yes)
			(layer "B.Fab")
			(hide yes)
			(effects
				(font
					(size 1.016 1.016)
					(thickness 0.1524)
				)
				(justify mirror)
			)
		)
		(duplicate_pad_numbers_are_jumpers no)
		(fp_line
			(start -0.635 0)
			(end 0.635 0)
			(stroke
				(width 0.508)
				(type default)
			)
			(layer "B.SilkS")
		)
		(fp_rect
			(start 0.9652 1.778)
			(end -0.9652 -1.778)
			(stroke
				(width 0)
				(type default)
			)
			(fill no)
			(layer "B.CrtYd")
		)
		(fp_poly
			(pts
				(xy 0.9652 -1.778) (xy -0.9652 -1.778) (xy -0.9652 1.778) (xy 0.9652 1.778)
			)
			(stroke
				(width 0)
				(type default)
			)
			(fill no)
			(layer "B.Fab")
		)
		(pad "1" smd rect
			(at 0 -0.9652 90)
			(size 1.397 1.143)
			(layers "B.Cu" "B.Mask" "B.Paste")
			(net "P0V9_E_VIN")
		)
		(pad "2" smd rect
			(at 0 0.9652 90)
			(size 1.397 1.143)
			(layers "B.Cu" "B.Mask" "B.Paste")
			(net "GND")
		)
	)
	(footprint ""
		(layer "B.Cu")
		(at 334.01 -63.627 90)
		(property "Reference" "PR154"
			(at 0 0 90)
			(layer "B.SilkS")
			(hide yes)
			(effects
				(font
					(size 1.27 1.27)
				)
				(justify mirror)
			)
		)
		(property "Value" "3D01R5F-GP"
			(at 0 -8.9535 90)
			(unlocked yes)
			(layer "B.Fab")
			(hide yes)
			(effects
				(font
					(size 1.27 1.016)
					(thickness 0.1524)
				)
				(justify mirror)
			)
		)
		(property "Device Type" "R805H24"
			(at 0 -10.6299 90)
			(unlocked yes)
			(layer "B.Fab")
			(hide yes)
			(effects
				(font
					(size 1.27 1.016)
					(thickness 0.1524)
				)
				(justify mirror)
			)
		)
		(duplicate_pad_numbers_are_jumpers no)
		(fp_line
			(start 0.889 -1.7018)
			(end 0.889 0.2794)
			(stroke
				(width 0.1524)
				(type default)
			)
			(layer "B.SilkS")
		)
		(fp_line
			(start -0.889 -1.7018)
			(end 0.889 -1.7018)
			(stroke
				(width 0.1524)
				(type default)
			)
			(layer "B.SilkS")
		)
		(fp_line
			(start -0.889 -1.7018)
			(end -0.889 -0.381)
			(stroke
				(width 0.1524)
				(type default)
			)
			(layer "B.SilkS")
		)
		(fp_line
			(start 0.889 0.0762)
			(end 0.889 1.7018)
			(stroke
				(width 0.1524)
				(type default)
			)
			(layer "B.SilkS")
		)
		(fp_line
			(start 0.889 1.7018)
			(end -0.889 1.7018)
			(stroke
				(width 0.1524)
				(type default)
			)
			(layer "B.SilkS")
		)
		(fp_line
			(start -0.889 1.7018)
			(end -0.889 -0.508)
			(stroke
				(width 0.1524)
				(type default)
			)
			(layer "B.SilkS")
		)
		(fp_poly
			(pts
				(xy -0.9652 -1.778) (xy -0.9652 1.778) (xy 0.9652 1.778) (xy 0.9652 -1.778)
			)
			(stroke
				(width 0)
				(type default)
			)
			(fill no)
			(layer "B.CrtYd")
		)
		(fp_rect
			(start 0.9652 1.778)
			(end -0.9652 -1.778)
			(stroke
				(width 0)
				(type default)
			)
			(fill no)
			(layer "B.Fab")
		)
		(pad "1" smd rect
			(at 0 -0.9652 270)
			(size 1.397 1.143)
			(layers "B.Cu" "B.Mask" "B.Paste")
			(net "P0V9_E_LX")
		)
		(pad "2" smd rect
			(at 0 0.9652 270)
			(size 1.397 1.143)
			(layers "B.Cu" "B.Mask" "B.Paste")
			(net "P0V9_E_SNB")
		)
	)
)
